(kicad_pcb
	(version 20260206)
	(generator "pcbnew")
	(generator_version "10.0")
	(general
		(thickness 1.6)
		(legacy_teardrops no)
	)
	(paper "A4")
	(title_block
		(title "01162023_DA0F0TEBIF0_F0T_Expander_BD_F_brd_V02_OCP.brd")
		(comment 1 "Grand Teton / footprints 7164-7169 of 9728")
	)
	(layers
		(0 "F.Cu" signal "TOP")
		(4 "In1.Cu" signal "GND")
		(6 "In2.Cu" signal "VCC")
		(8 "In3.Cu" signal "VCC1")
		(10 "In4.Cu" signal "GND1")
		(12 "In5.Cu" signal "IN1")
		(14 "In6.Cu" signal "GND2")
		(16 "In7.Cu" signal "IN2")
		(18 "In8.Cu" signal "GND3")
		(20 "In9.Cu" signal "IN3")
		(22 "In10.Cu" signal "GND4")
		(24 "In11.Cu" signal "IN4")
		(26 "In12.Cu" signal "GND5")
		(28 "In13.Cu" signal "IN5")
		(30 "In14.Cu" signal "GND6")
		(32 "In15.Cu" signal "IN6")
		(34 "In16.Cu" signal "GND7")
		(2 "B.Cu" signal "BOTTOM")
		(9 "F.Adhes" user "F.Adhesive")
		(11 "B.Adhes" user "B.Adhesive")
		(13 "F.Paste" user "Package Geometry/Pastemask Top")
		(15 "B.Paste" user "Package Geometry/Pastemask Bottom")
		(5 "F.SilkS" user "Ref Des/Silkscreen Top")
		(7 "B.SilkS" user "Ref Des/Silkscreen Bottom")
		(1 "F.Mask" user "Board Geometry/Soldermask Top")
		(3 "B.Mask" user "Board Geometry/Soldermask Bottom")
		(17 "Dwgs.User" user "User.Drawings")
		(19 "Cmts.User" user "User.Comments")
		(21 "Eco1.User" user "User.Eco1")
		(23 "Eco2.User" user "User.Eco2")
		(25 "Edge.Cuts" user "Board Geometry/Outline")
		(27 "Margin" user)
		(31 "F.CrtYd" user "Package Geometry/Place Bound Top")
		(29 "B.CrtYd" user "Package Geometry/Place Bound Bottom")
		(35 "F.Fab" user "Ref Des/Assembly Top")
		(33 "B.Fab" user "Ref Des/Assembly Bottom")
	)
	(footprint ""
		(layer "B.Cu")
		(at 217.235786 -223.382586)
		(property "Reference" "R1496"
			(at 0 0 0)
			(layer "B.SilkS")
			(hide yes)
			(effects
				(font
					(size 1.27 1.27)
				)
				(justify mirror)
			)
		)
		(property "Value" ""
			(at 0 0 0)
			(layer "B.Fab")
			(effects
				(font
					(size 1.27 1.27)
				)
				(justify mirror)
			)
		)
		(duplicate_pad_numbers_are_jumpers no)
		(fp_line
			(start -0.7874 -0.4064)
			(end -0.7874 0.4064)
			(stroke
				(width 0.1524)
				(type default)
			)
			(layer "B.SilkS")
		)
		(fp_line
			(start -0.7874 0.4064)
			(end 0.7874 0.4064)
			(stroke
				(width 0.1524)
				(type default)
			)
			(layer "B.SilkS")
		)
		(fp_line
			(start 0.7874 -0.4064)
			(end -0.7874 -0.4064)
			(stroke
				(width 0.1524)
				(type default)
			)
			(layer "B.SilkS")
		)
		(fp_line
			(start 0.7874 0.4064)
			(end 0.7874 -0.4064)
			(stroke
				(width 0.1524)
				(type default)
			)
			(layer "B.SilkS")
		)
		(fp_line
			(start -0.67945 -0.3048)
			(end -0.67945 0.3048)
			(stroke
				(width 0.1)
				(type default)
			)
			(layer "B.Fab")
		)
		(fp_line
			(start -0.67945 0.3048)
			(end -0.120396 0.3048)
			(stroke
				(width 0.1)
				(type default)
			)
			(layer "B.Fab")
		)
		(fp_line
			(start -0.12065 -0.3048)
			(end -0.67945 -0.3048)
			(stroke
				(width 0.1)
				(type default)
			)
			(layer "B.Fab")
		)
		(fp_line
			(start -0.12065 -0.2794)
			(end -0.12065 -0.3048)
			(stroke
				(width 0.1)
				(type default)
			)
			(layer "B.Fab")
		)
		(fp_line
			(start -0.120396 0.2794)
			(end 0.12065 0.2794)
			(stroke
				(width 0.1)
				(type default)
			)
			(layer "B.Fab")
		)
		(fp_line
			(start -0.120396 0.3048)
			(end -0.120396 0.2794)
			(stroke
				(width 0.1)
				(type default)
			)
			(layer "B.Fab")
		)
		(fp_line
			(start 0.12065 -0.305054)
			(end 0.12065 -0.2794)
			(stroke
				(width 0.1)
				(type default)
			)
			(layer "B.Fab")
		)
		(fp_line
			(start 0.12065 -0.2794)
			(end -0.12065 -0.2794)
			(stroke
				(width 0.1)
				(type default)
			)
			(layer "B.Fab")
		)
		(fp_line
			(start 0.12065 0.2794)
			(end 0.12065 0.3048)
			(stroke
				(width 0.1)
				(type default)
			)
			(layer "B.Fab")
		)
		(fp_line
			(start 0.12065 0.3048)
			(end 0.67945 0.3048)
			(stroke
				(width 0.1)
				(type default)
			)
			(layer "B.Fab")
		)
		(fp_line
			(start 0.67945 -0.305054)
			(end 0.12065 -0.305054)
			(stroke
				(width 0.1)
				(type default)
			)
			(layer "B.Fab")
		)
		(fp_line
			(start 0.67945 0.3048)
			(end 0.67945 -0.305054)
			(stroke
				(width 0.1)
				(type default)
			)
			(layer "B.Fab")
		)
		(pad "1" smd circle
			(at 0.40005 0 180)
			(size 0 0)
			(layers "B.Cu" "B.Mask" "B.Paste")
			(net "SMB_BIC_I2C6_SDA")
		)
		(pad "2" smd circle
			(at -0.40005 0 180)
			(size 0 0)
			(layers "B.Cu" "B.Mask" "B.Paste")
			(net "SMB_BIC_I2C6_R_SDA")
		)
	)
	(footprint ""
		(layer "B.Cu")
		(at 387.223 -239.522 180)
		(property "Reference" "R939"
			(at 0 0 0)
			(layer "B.SilkS")
			(hide yes)
			(effects
				(font
					(size 1.27 1.27)
				)
				(justify mirror)
			)
		)
		(property "Value" ""
			(at 0 0 0)
			(layer "B.Fab")
			(effects
				(font
					(size 1.27 1.27)
				)
				(justify mirror)
			)
		)
		(duplicate_pad_numbers_are_jumpers no)
		(fp_line
			(start 0.7874 0.4064)
			(end 0.7874 -0.4064)
			(stroke
				(width 0.1524)
				(type default)
			)
			(layer "B.SilkS")
		)
		(fp_line
			(start 0.7874 -0.4064)
			(end -0.7874 -0.4064)
			(stroke
				(width 0.1524)
				(type default)
			)
			(layer "B.SilkS")
		)
		(fp_line
			(start -0.7874 0.4064)
			(end 0.7874 0.4064)
			(stroke
				(width 0.1524)
				(type default)
			)
			(layer "B.SilkS")
		)
		(fp_line
			(start -0.7874 -0.4064)
			(end -0.7874 0.4064)
			(stroke
				(width 0.1524)
				(type default)
			)
			(layer "B.SilkS")
		)
		(fp_line
			(start 0.67945 0.3048)
			(end 0.67945 -0.305054)
			(stroke
				(width 0.1)
				(type default)
			)
			(layer "B.Fab")
		)
		(fp_line
			(start 0.67945 -0.305054)
			(end 0.12065 -0.305054)
			(stroke
				(width 0.1)
				(type default)
			)
			(layer "B.Fab")
		)
		(fp_line
			(start 0.12065 0.3048)
			(end 0.67945 0.3048)
			(stroke
				(width 0.1)
				(type default)
			)
			(layer "B.Fab")
		)
		(fp_line
			(start 0.12065 0.2794)
			(end 0.12065 0.3048)
			(stroke
				(width 0.1)
				(type default)
			)
			(layer "B.Fab")
		)
		(fp_line
			(start 0.12065 -0.2794)
			(end -0.12065 -0.2794)
			(stroke
				(width 0.1)
				(type default)
			)
			(layer "B.Fab")
		)
		(fp_line
			(start 0.12065 -0.305054)
			(end 0.12065 -0.2794)
			(stroke
				(width 0.1)
				(type default)
			)
			(layer "B.Fab")
		)
		(fp_line
			(start -0.120396 0.3048)
			(end -0.120396 0.2794)
			(stroke
				(width 0.1)
				(type default)
			)
			(layer "B.Fab")
		)
		(fp_line
			(start -0.120396 0.2794)
			(end 0.12065 0.2794)
			(stroke
				(width 0.1)
				(type default)
			)
			(layer "B.Fab")
		)
		(fp_line
			(start -0.12065 -0.2794)
			(end -0.12065 -0.3048)
			(stroke
				(width 0.1)
				(type default)
			)
			(layer "B.Fab")
		)
		(fp_line
			(start -0.12065 -0.3048)
			(end -0.67945 -0.3048)
			(stroke
				(width 0.1)
				(type default)
			)
			(layer "B.Fab")
		)
		(fp_line
			(start -0.67945 0.3048)
			(end -0.120396 0.3048)
			(stroke
				(width 0.1)
				(type default)
			)
			(layer "B.Fab")
		)
		(fp_line
			(start -0.67945 -0.3048)
			(end -0.67945 0.3048)
			(stroke
				(width 0.1)
				(type default)
			)
			(layer "B.Fab")
		)
		(pad "1" smd circle
			(at 0.40005 0)
			(size 0 0)
			(layers "B.Cu" "B.Mask" "B.Paste")
			(net "UART_PEX2_SDB_RX")
		)
		(pad "2" smd circle
			(at -0.40005 0)
			(size 0 0)
			(layers "B.Cu" "B.Mask" "B.Paste")
			(net "UART_PEX2_SDB_R_RX")
		)
	)
	(footprint ""
		(layer "B.Cu")
		(at 78.345792 -450.581014 180)
		(property "Reference" "X65"
			(at 0.1778 -1.92913 180)
			(unlocked yes)
			(layer "B.SilkS")
			(effects
				(font
					(size 0.7874 0.5842)
					(thickness 0.1524)
				)
				(justify left mirror)
			)
		)
		(property "Value" ""
			(at 0 0 0)
			(layer "B.Fab")
			(effects
				(font
					(size 1.27 1.27)
				)
				(justify mirror)
			)
		)
		(property "Device Type" "TP_TDR_4P_FTS_MPKT4_H025P0200_IO_TP15_TP_TDR_4P_DIP"
			(at -1.30175 1.27 90)
			(unlocked yes)
			(layer "B.Fab")
			(hide yes)
			(effects
				(font
					(size 0.635 0.4064)
					(thickness 0.1524)
				)
				(justify mirror)
			)
		)
		(property "User Part Number" "TP15"
			(at -1.30175 1.27 90)
			(unlocked yes)
			(layer "Cmts.User")
			(hide yes)
			(effects
				(font
					(size 0.635 0.4064)
					(thickness 0.1524)
				)
				(justify mirror)
			)
		)
		(duplicate_pad_numbers_are_jumpers no)
		(fp_line
			(start 0 3.81)
			(end -2.54 3.81)
			(stroke
				(width 0.1524)
				(type default)
			)
			(layer "B.SilkS")
		)
		(fp_line
			(start 0 3.175)
			(end 0 3.81)
			(stroke
				(width 0.1524)
				(type default)
			)
			(layer "B.SilkS")
		)
		(fp_line
			(start 0 0.635)
			(end 0 1.905)
			(stroke
				(width 0.1524)
				(type default)
			)
			(layer "B.SilkS")
		)
		(fp_line
			(start 0 -1.27)
			(end 0 -0.635)
			(stroke
				(width 0.1524)
				(type default)
			)
			(layer "B.SilkS")
		)
		(fp_line
			(start -2.54 3.81)
			(end -2.54 3.6703)
			(stroke
				(width 0.1524)
				(type default)
			)
			(layer "B.SilkS")
		)
		(fp_line
			(start -2.54 1.4097)
			(end -2.54 1.1303)
			(stroke
				(width 0.1524)
				(type default)
			)
			(layer "B.SilkS")
		)
		(fp_line
			(start -2.54 -1.1303)
			(end -2.54 -1.27)
			(stroke
				(width 0.1524)
				(type default)
			)
			(layer "B.SilkS")
		)
		(fp_line
			(start -2.54 -1.27)
			(end 0 -1.27)
			(stroke
				(width 0.1524)
				(type default)
			)
			(layer "B.SilkS")
		)
		(fp_poly
			(pts
				(xy 0.761746 0) (xy 2.285746 -0.762) (xy 2.285746 0.762)
			)
			(stroke
				(width 0)
				(type default)
			)
			(fill yes)
			(layer "B.SilkS")
		)
		(fp_line
			(start 0 3.81)
			(end -2.54 3.81)
			(stroke
				(width 0.1)
				(type default)
			)
			(layer "B.Fab")
		)
		(fp_line
			(start 0 -1.27)
			(end 0 3.81)
			(stroke
				(width 0.1)
				(type default)
			)
			(layer "B.Fab")
		)
		(fp_line
			(start -2.54 3.81)
			(end -2.54 -1.27)
			(stroke
				(width 0.1)
				(type default)
			)
			(layer "B.Fab")
		)
		(fp_line
			(start -2.54 -1.27)
			(end 0 -1.27)
			(stroke
				(width 0.1)
				(type default)
			)
			(layer "B.Fab")
		)
		(fp_poly
			(pts
				(xy 0.761746 0) (xy 2.285746 -0.762) (xy 2.285746 0.762)
			)
			(stroke
				(width 0)
				(type default)
			)
			(fill yes)
			(layer "B.Fab")
		)
		(pad "1" thru_hole circle
			(at 0 0)
			(size 1.0033 1.0033)
			(drill 0.249936)
			(layers "*.Cu" "*.Mask")
			(remove_unused_layers no)
			(net "TDR_DIFF_85_IN6_DIN")
			(clearance 0.10795)
			(padstack
				(mode front_inner_back)
				(layer "Inner"
					(shape circle)
					(size 0.8001 0.8001)
					(clearance 0.1524)
				)
				(layer "B.Cu"
					(shape circle)
					(size 1.0033 1.0033)
					(thermal_gap 0.10795)
					(clearance 0.10795)
				)
			)
		)
		(pad "2" thru_hole circle
			(at -2.54 0)
			(size 1.9939 1.9939)
			(drill 0.249936)
			(layers "*.Cu" "*.Mask")
			(remove_unused_layers no)
			(net "COUPON_GND1")
			(clearance 0.10795)
			(padstack
				(mode front_inner_back)
				(layer "Inner"
					(shape circle)
					(size 0.8001 0.8001)
					(clearance 0.1524)
				)
				(layer "B.Cu"
					(shape circle)
					(size 1.9939 1.9939)
					(thermal_gap 0.10795)
					(clearance 0.10795)
				)
			)
		)
		(pad "3" thru_hole circle
			(at -2.54 2.54)
			(size 1.9939 1.9939)
			(drill 0.249936)
			(layers "*.Cu" "*.Mask")
			(remove_unused_layers no)
			(net "COUPON_GND1")
			(clearance 0.10795)
			(padstack
				(mode front_inner_back)
				(layer "Inner"
					(shape circle)
					(size 0.8001 0.8001)
					(clearance 0.1524)
				)
				(layer "B.Cu"
					(shape circle)
					(size 1.9939 1.9939)
					(thermal_gap 0.10795)
					(clearance 0.10795)
				)
			)
		)
		(pad "4" thru_hole circle
			(at 0 2.54)
			(size 1.0033 1.0033)
			(drill 0.249936)
			(layers "*.Cu" "*.Mask")
			(remove_unused_layers no)
			(net "TDR_DIFF_85_IN6_DIP")
			(clearance 0.10795)
			(padstack
				(mode front_inner_back)
				(layer "Inner"
					(shape circle)
					(size 0.8001 0.8001)
					(clearance 0.1524)
				)
				(layer "B.Cu"
					(shape circle)
					(size 1.0033 1.0033)
					(thermal_gap 0.10795)
					(clearance 0.10795)
				)
			)
		)
	)
	(footprint ""
		(layer "B.Cu")
		(at 301.349918 -301.124874)
		(property "Reference" "C3339"
			(at 0 0 0)
			(layer "B.SilkS")
			(hide yes)
			(effects
				(font
					(size 1.27 1.27)
				)
				(justify mirror)
			)
		)
		(property "Value" ""
			(at 0 0 0)
			(layer "B.Fab")
			(effects
				(font
					(size 1.27 1.27)
				)
				(justify mirror)
			)
		)
		(duplicate_pad_numbers_are_jumpers no)
		(fp_line
			(start -0.299974 -0.150114)
			(end -0.299974 0.150114)
			(stroke
				(width 0.1)
				(type default)
			)
			(layer "B.Fab")
		)
		(fp_line
			(start -0.299974 0.150114)
			(end 0.299974 0.150114)
			(stroke
				(width 0.1)
				(type default)
			)
			(layer "B.Fab")
		)
		(fp_line
			(start 0.299974 -0.150114)
			(end -0.299974 -0.150114)
			(stroke
				(width 0.1)
				(type default)
			)
			(layer "B.Fab")
		)
		(fp_line
			(start 0.299974 0.150114)
			(end 0.299974 -0.150114)
			(stroke
				(width 0.1)
				(type default)
			)
			(layer "B.Fab")
		)
		(pad "1" smd rect
			(at 0.2667 0 180)
			(size 0.3048 0.381)
			(layers "B.Cu" "B.Mask" "B.Paste")
			(net "P1V8_PEX")
		)
		(pad "2" smd rect
			(at -0.2667 0 180)
			(size 0.3048 0.381)
			(layers "B.Cu" "B.Mask" "B.Paste")
			(net "GND")
		)
	)
	(footprint ""
		(layer "B.Cu")
		(at 385.445 -239.522 180)
		(property "Reference" "R940"
			(at 0 0 0)
			(layer "B.SilkS")
			(hide yes)
			(effects
				(font
					(size 1.27 1.27)
				)
				(justify mirror)
			)
		)
		(property "Value" ""
			(at 0 0 0)
			(layer "B.Fab")
			(effects
				(font
					(size 1.27 1.27)
				)
				(justify mirror)
			)
		)
		(duplicate_pad_numbers_are_jumpers no)
		(fp_line
			(start 0.7874 0.4064)
			(end 0.7874 -0.4064)
			(stroke
				(width 0.1524)
				(type default)
			)
			(layer "B.SilkS")
		)
		(fp_line
			(start 0.7874 -0.4064)
			(end -0.7874 -0.4064)
			(stroke
				(width 0.1524)
				(type default)
			)
			(layer "B.SilkS")
		)
		(fp_line
			(start -0.7874 0.4064)
			(end 0.7874 0.4064)
			(stroke
				(width 0.1524)
				(type default)
			)
			(layer "B.SilkS")
		)
		(fp_line
			(start -0.7874 -0.4064)
			(end -0.7874 0.4064)
			(stroke
				(width 0.1524)
				(type default)
			)
			(layer "B.SilkS")
		)
		(fp_line
			(start 0.67945 0.3048)
			(end 0.67945 -0.305054)
			(stroke
				(width 0.1)
				(type default)
			)
			(layer "B.Fab")
		)
		(fp_line
			(start 0.67945 -0.305054)
			(end 0.12065 -0.305054)
			(stroke
				(width 0.1)
				(type default)
			)
			(layer "B.Fab")
		)
		(fp_line
			(start 0.12065 0.3048)
			(end 0.67945 0.3048)
			(stroke
				(width 0.1)
				(type default)
			)
			(layer "B.Fab")
		)
		(fp_line
			(start 0.12065 0.2794)
			(end 0.12065 0.3048)
			(stroke
				(width 0.1)
				(type default)
			)
			(layer "B.Fab")
		)
		(fp_line
			(start 0.12065 -0.2794)
			(end -0.12065 -0.2794)
			(stroke
				(width 0.1)
				(type default)
			)
			(layer "B.Fab")
		)
		(fp_line
			(start 0.12065 -0.305054)
			(end 0.12065 -0.2794)
			(stroke
				(width 0.1)
				(type default)
			)
			(layer "B.Fab")
		)
		(fp_line
			(start -0.120396 0.3048)
			(end -0.120396 0.2794)
			(stroke
				(width 0.1)
				(type default)
			)
			(layer "B.Fab")
		)
		(fp_line
			(start -0.120396 0.2794)
			(end 0.12065 0.2794)
			(stroke
				(width 0.1)
				(type default)
			)
			(layer "B.Fab")
		)
		(fp_line
			(start -0.12065 -0.2794)
			(end -0.12065 -0.3048)
			(stroke
				(width 0.1)
				(type default)
			)
			(layer "B.Fab")
		)
		(fp_line
			(start -0.12065 -0.3048)
			(end -0.67945 -0.3048)
			(stroke
				(width 0.1)
				(type default)
			)
			(layer "B.Fab")
		)
		(fp_line
			(start -0.67945 0.3048)
			(end -0.120396 0.3048)
			(stroke
				(width 0.1)
				(type default)
			)
			(layer "B.Fab")
		)
		(fp_line
			(start -0.67945 -0.3048)
			(end -0.67945 0.3048)
			(stroke
				(width 0.1)
				(type default)
			)
			(layer "B.Fab")
		)
		(pad "1" smd circle
			(at 0.40005 0)
			(size 0 0)
			(layers "B.Cu" "B.Mask" "B.Paste")
			(net "UART_PEX3_SDB_RX")
		)
		(pad "2" smd circle
			(at -0.40005 0)
			(size 0 0)
			(layers "B.Cu" "B.Mask" "B.Paste")
			(net "UART_PEX3_SDB_R_RX")
		)
	)
	(footprint ""
		(layer "B.Cu")
		(at 290.89985 -292.099746 90)
		(property "Reference" "C1671"
			(at 0 0 90)
			(layer "B.SilkS")
			(hide yes)
			(effects
				(font
					(size 1.27 1.27)
				)
				(justify mirror)
			)
		)
		(property "Value" ""
			(at 0 0 90)
			(layer "B.Fab")
			(effects
				(font
					(size 1.27 1.27)
				)
				(justify mirror)
			)
		)
		(duplicate_pad_numbers_are_jumpers no)
		(fp_line
			(start 0.299974 -0.150114)
			(end -0.299974 -0.150114)
			(stroke
				(width 0.1)
				(type default)
			)
			(layer "B.Fab")
		)
		(fp_line
			(start -0.299974 -0.150114)
			(end -0.299974 0.150114)
			(stroke
				(width 0.1)
				(type default)
			)
			(layer "B.Fab")
		)
		(fp_line
			(start 0.299974 0.150114)
			(end 0.299974 -0.150114)
			(stroke
				(width 0.1)
				(type default)
			)
			(layer "B.Fab")
		)
		(fp_line
			(start -0.299974 0.150114)
			(end 0.299974 0.150114)
			(stroke
				(width 0.1)
				(type default)
			)
			(layer "B.Fab")
		)
		(pad "1" smd rect
			(at 0.2667 0 270)
			(size 0.3048 0.381)
			(layers "B.Cu" "B.Mask" "B.Paste")
			(net "P0V8_SERDES_VDDA_PEX2")
		)
		(pad "2" smd rect
			(at -0.2667 0 270)
			(size 0.3048 0.381)
			(layers "B.Cu" "B.Mask" "B.Paste")
			(net "GND")
		)
	)
)
